(kicad_pcb
	(version 20260206)
	(generator "pcbnew")
	(generator_version "10.0")
	(general
		(thickness 1.6)
		(legacy_teardrops no)
	)
	(paper "A4")
	(title_block
		(title "04192023_DAF0TMB3IC0_F0TG_MB_C_brd_V02_OCP.brd")
		(comment 1 "Grand Teton / footprint 2783 of 8354 (U26), pads 4901-5011 of 6102")
	)
	(layers
		(0 "F.Cu" signal "TOP")
		(4 "In1.Cu" signal "GND")
		(6 "In2.Cu" signal "IN1")
		(8 "In3.Cu" signal "GND1")
		(10 "In4.Cu" signal "IN2")
		(12 "In5.Cu" signal "GND2")
		(14 "In6.Cu" signal "IN3")
		(16 "In7.Cu" signal "GND3")
		(18 "In8.Cu" signal "VCC")
		(20 "In9.Cu" signal "VCC1")
		(22 "In10.Cu" signal "GND4")
		(24 "In11.Cu" signal "IN4")
		(26 "In12.Cu" signal "GND5")
		(28 "In13.Cu" signal "IN5")
		(30 "In14.Cu" signal "GND6")
		(32 "In15.Cu" signal "IN6")
		(34 "In16.Cu" signal "GND7")
		(2 "B.Cu" signal "BOTTOM")
		(9 "F.Adhes" user "F.Adhesive")
		(11 "B.Adhes" user "B.Adhesive")
		(13 "F.Paste" user "Package Geometry/Pastemask Top")
		(15 "B.Paste" user "Package Geometry/Pastemask Bottom")
		(5 "F.SilkS" user "Ref Des/Silkscreen Top")
		(7 "B.SilkS" user "Ref Des/Silkscreen Bottom")
		(1 "F.Mask" user "Board Geometry/Soldermask Top")
		(3 "B.Mask" user "Board Geometry/Soldermask Bottom")
		(17 "Dwgs.User" user "User.Drawings")
		(19 "Cmts.User" user "User.Comments")
		(21 "Eco1.User" user "User.Eco1")
		(23 "Eco2.User" user "User.Eco2")
		(25 "Edge.Cuts" user "Board Geometry/Outline")
		(27 "Margin" user)
		(31 "F.CrtYd" user "Package Geometry/Place Bound Top")
		(29 "B.CrtYd" user "Package Geometry/Place Bound Bottom")
		(35 "F.Fab" user "Ref Des/Assembly Top")
		(33 "B.Fab" user "Ref Des/Assembly Bottom")
	)
	(footprint ""
		(layer "F.Cu")
		(at 111.927894 -258.880356 180)
		(property "Reference" "U26"
			(at -45.05579 -61.794136 0)
			(unlocked yes)
			(layer "F.SilkS")
			(effects
				(font
					(size 0.7874 0.5842)
					(thickness 0.1524)
				)
			)
		)
		(property "Value" ""
			(at 0 0 180)
			(layer "F.Fab")
			(effects
				(font
					(size 1.27 1.27)
				)
			)
		)
		(duplicate_pad_numbers_are_jumpers no)
		(pad "DJ10" smd circle
			(at -25.999948 36.809934 180)
			(size 0.450088 0.450088)
			(layers "F.Cu" "F.Mask" "F.Paste")
			(net "IRQ_WAKE_N")
		)
		(pad "DJ11" smd circle
			(at -25.059894 36.809934 180)
			(size 0.450088 0.450088)
			(layers "F.Cu" "F.Mask" "F.Paste")
			(net "CPU1_SMERR_N")
		)
		(pad "DJ13" smd circle
			(at -23.18004 36.809934 180)
			(size 0.450088 0.450088)
			(layers "F.Cu" "F.Mask" "F.Paste")
			(net "XTAL_CPU1_X32K_X2")
		)
		(pad "DJ14" smd circle
			(at -22.239986 36.809934 180)
			(size 0.450088 0.450088)
			(layers "F.Cu" "F.Mask" "F.Paste")
			(net "XTAL_CPU1_X32K_X1")
		)
		(pad "DJ15" smd circle
			(at -21.299932 36.809934 180)
			(size 0.450088 0.450088)
			(layers "F.Cu" "F.Mask" "F.Paste")
			(net "GND")
		)
		(pad "DJ16" smd circle
			(at -20.359878 36.809934 180)
			(size 0.450088 0.450088)
			(layers "F.Cu" "F.Mask" "F.Paste")
			(net "XTAL_CPU1_X48M_X2")
		)
		(pad "DJ17" smd circle
			(at -19.420078 36.809934 180)
			(size 0.450088 0.450088)
			(layers "F.Cu" "F.Mask" "F.Paste")
			(net "XTAL_CPU1_X48M_X1")
		)
		(pad "DJ19" smd circle
			(at -17.53997 36.809934 180)
			(size 0.450088 0.450088)
			(layers "F.Cu" "F.Mask" "F.Paste")
			(net "GND")
		)
		(pad "DJ20" smd circle
			(at -16.599916 36.809934 180)
			(size 0.450088 0.450088)
			(layers "F.Cu" "F.Mask" "F.Paste")
			(net "Net_2095")
		)
		(pad "DJ21" smd circle
			(at -15.660116 36.809934 180)
			(size 0.450088 0.450088)
			(layers "F.Cu" "F.Mask" "F.Paste")
			(net "Net_2094")
		)
		(pad "DJ22" smd circle
			(at -14.720062 36.809934 180)
			(size 0.450088 0.450088)
			(layers "F.Cu" "F.Mask" "F.Paste")
			(net "Net_2103")
		)
		(pad "DJ23" smd circle
			(at -13.780008 36.809934 180)
			(size 0.450088 0.450088)
			(layers "F.Cu" "F.Mask" "F.Paste")
			(net "Net_2115")
		)
		(pad "DJ25" smd circle
			(at -11.8999 36.809934 180)
			(size 0.450088 0.450088)
			(layers "F.Cu" "F.Mask" "F.Paste")
			(net "Net_2102")
		)
		(pad "DJ26" smd circle
			(at -10.9601 36.809934 180)
			(size 0.450088 0.450088)
			(layers "F.Cu" "F.Mask" "F.Paste")
			(net "Net_2116")
		)
		(pad "DJ27" smd circle
			(at -10.020046 36.809934 180)
			(size 0.450088 0.450088)
			(layers "F.Cu" "F.Mask" "F.Paste")
			(net "SPI_CPU1_R_CLK")
		)
		(pad "DJ28" smd circle
			(at -9.079992 36.809934 180)
			(size 0.450088 0.450088)
			(layers "F.Cu" "F.Mask" "F.Paste")
			(net "Net_2106")
		)
		(pad "DJ29" smd circle
			(at -8.139938 36.809934 180)
			(size 0.450088 0.450088)
			(layers "F.Cu" "F.Mask" "F.Paste")
			(net "Net_2087")
		)
		(pad "DJ31" smd circle
			(at -6.260084 36.809934 180)
			(size 0.450088 0.450088)
			(layers "F.Cu" "F.Mask" "F.Paste")
			(net "CPU1_NMI_SYNC_FLOOD_N")
		)
		(pad "DJ32" smd circle
			(at -5.32003 36.809934 180)
			(size 0.450088 0.450088)
			(layers "F.Cu" "F.Mask" "F.Paste")
			(net "Net_2074")
		)
		(pad "DJ33" smd circle
			(at -4.379976 36.809934 180)
			(size 0.450088 0.450088)
			(layers "F.Cu" "F.Mask" "F.Paste")
			(net "TP_CPU1_UART0_CTS_N")
		)
		(pad "DJ34" smd circle
			(at -3.439922 36.809934 180)
			(size 0.450088 0.450088)
			(layers "F.Cu" "F.Mask" "F.Paste")
			(net "TP_CPU1_UART0_TX")
		)
		(pad "DJ35" smd circle
			(at -2.500122 36.809934 180)
			(size 0.450088 0.450088)
			(layers "F.Cu" "F.Mask" "F.Paste")
			(net "INT_CPU1_HP_UBM_N")
		)
		(pad "DJ41" smd circle
			(at 2.199894 36.809934 180)
			(size 0.450088 0.450088)
			(layers "F.Cu" "F.Mask" "F.Paste")
			(net "CLK_100M_CPU1_CLK11_R_DP")
		)
		(pad "DJ42" smd circle
			(at 3.139948 36.809934 180)
			(size 0.450088 0.450088)
			(layers "F.Cu" "F.Mask" "F.Paste")
			(net "CLK_100M_CPU1_CLK11_R_DN")
		)
		(pad "DJ43" smd circle
			(at 4.080002 36.809934 180)
			(size 0.450088 0.450088)
			(layers "F.Cu" "F.Mask" "F.Paste")
			(net "GND")
		)
		(pad "DJ44" smd circle
			(at 5.020056 36.809934 180)
			(size 0.450088 0.450088)
			(layers "F.Cu" "F.Mask" "F.Paste")
			(net "CLK_100M_CPU1_CLK12_R_DN")
		)
		(pad "DJ45" smd circle
			(at 5.96011 36.809934 180)
			(size 0.450088 0.450088)
			(layers "F.Cu" "F.Mask" "F.Paste")
			(net "CLK_100M_CPU1_CLK12_R_DP")
		)
		(pad "DJ47" smd circle
			(at 7.839964 36.809934 180)
			(size 0.450088 0.450088)
			(layers "F.Cu" "F.Mask" "F.Paste")
			(net "Net_2088")
		)
		(pad "DJ48" smd circle
			(at 8.780018 36.809934 180)
			(size 0.450088 0.450088)
			(layers "F.Cu" "F.Mask" "F.Paste")
			(net "Net_2089")
		)
		(pad "DJ49" smd circle
			(at 9.720072 36.809934 180)
			(size 0.450088 0.450088)
			(layers "F.Cu" "F.Mask" "F.Paste")
			(net "GND")
		)
		(pad "DJ50" smd circle
			(at 10.659872 36.809934 180)
			(size 0.450088 0.450088)
			(layers "F.Cu" "F.Mask" "F.Paste")
			(net "Net_2090")
		)
		(pad "DJ51" smd circle
			(at 11.599926 36.809934 180)
			(size 0.450088 0.450088)
			(layers "F.Cu" "F.Mask" "F.Paste")
			(net "Net_2091")
		)
		(pad "DJ53" smd circle
			(at 13.480034 36.809934 180)
			(size 0.450088 0.450088)
			(layers "F.Cu" "F.Mask" "F.Paste")
			(net "CLK_100M_CPU1_CLK13_R_DP")
		)
		(pad "DJ54" smd circle
			(at 14.420088 36.809934 180)
			(size 0.450088 0.450088)
			(layers "F.Cu" "F.Mask" "F.Paste")
			(net "CLK_100M_CPU1_CLK13_R_DN")
		)
		(pad "DJ55" smd circle
			(at 15.359888 36.809934 180)
			(size 0.450088 0.450088)
			(layers "F.Cu" "F.Mask" "F.Paste")
			(net "CPU1_SA0")
		)
		(pad "DJ56" smd circle
			(at 16.299942 36.809934 180)
			(size 0.450088 0.450088)
			(layers "F.Cu" "F.Mask" "F.Paste")
			(net "CPU1_SA1")
		)
		(pad "DJ57" smd circle
			(at 17.239996 36.809934 180)
			(size 0.450088 0.450088)
			(layers "F.Cu" "F.Mask" "F.Paste")
			(net "Net_2178")
		)
		(pad "DJ59" smd circle
			(at 19.120104 36.809934 180)
			(size 0.450088 0.450088)
			(layers "F.Cu" "F.Mask" "F.Paste")
			(net "GND")
		)
		(pad "DJ60" smd circle
			(at 20.059904 36.809934 180)
			(size 0.450088 0.450088)
			(layers "F.Cu" "F.Mask" "F.Paste")
			(net "NC_CPU1_USB2_USB11_DN")
		)
		(pad "DJ61" smd circle
			(at 20.999958 36.809934 180)
			(size 0.450088 0.450088)
			(layers "F.Cu" "F.Mask" "F.Paste")
			(net "GND")
		)
		(pad "DJ62" smd circle
			(at 21.940012 36.809934 180)
			(size 0.450088 0.450088)
			(layers "F.Cu" "F.Mask" "F.Paste")
			(net "NC_CPU1_USB3_USB11_RXP")
		)
		(pad "DJ63" smd circle
			(at 22.880066 36.809934 180)
			(size 0.450088 0.450088)
			(layers "F.Cu" "F.Mask" "F.Paste")
			(net "GND")
		)
		(pad "DJ65" smd circle
			(at 24.75992 36.809934 180)
			(size 0.450088 0.450088)
			(layers "F.Cu" "F.Mask" "F.Paste")
			(net "NC_CPU1_USB3_USB10_RXP")
		)
		(pad "DJ66" smd circle
			(at 25.699974 36.809934 180)
			(size 0.450088 0.450088)
			(layers "F.Cu" "F.Mask" "F.Paste")
			(net "GND")
		)
		(pad "DJ67" smd circle
			(at 26.640028 36.809934 180)
			(size 0.450088 0.450088)
			(layers "F.Cu" "F.Mask" "F.Paste")
			(net "NC_CPU1_USB2_USB10_DP")
		)
		(pad "DJ68" smd circle
			(at 27.580082 36.809934 180)
			(size 0.450088 0.450088)
			(layers "F.Cu" "F.Mask" "F.Paste")
			(net "GND")
		)
		(pad "DJ69" smd circle
			(at 28.519882 36.809934 180)
			(size 0.450088 0.450088)
			(layers "F.Cu" "F.Mask" "F.Paste")
			(net "NC_CPU1_USB3_USB10_TXN")
		)
		(pad "DJ71" smd circle
			(at 30.39999 36.809934 180)
			(size 0.450088 0.450088)
			(layers "F.Cu" "F.Mask" "F.Paste")
			(net "SMB_APML_CPU1_SCL")
		)
		(pad "DJ72" smd circle
			(at 31.340044 36.809934 180)
			(size 0.450088 0.450088)
			(layers "F.Cu" "F.Mask" "F.Paste")
			(net "SVID_PVDDCR_CPU1_P1_SVC")
		)
		(pad "DJ73" smd circle
			(at 32.280098 36.809934 180)
			(size 0.450088 0.450088)
			(layers "F.Cu" "F.Mask" "F.Paste")
			(net "GND")
		)
		(pad "E1" smd circle
			(at -34.159952 -33.56991 180)
			(size 0.450088 0.450088)
			(layers "F.Cu" "F.Mask" "F.Paste")
			(net "GND")
		)
		(pad "E2" smd circle
			(at -33.219898 -33.56991 180)
			(size 0.450088 0.450088)
			(layers "F.Cu" "F.Mask" "F.Paste")
			(net "M_G_CPU1_SA_DQ<0>")
		)
		(pad "E3" smd circle
			(at -32.280098 -33.56991 180)
			(size 0.450088 0.450088)
			(layers "F.Cu" "F.Mask" "F.Paste")
			(net "GND")
		)
		(pad "E4" smd circle
			(at -31.340044 -33.56991 180)
			(size 0.450088 0.450088)
			(layers "F.Cu" "F.Mask" "F.Paste")
			(net "PVDDCR_SOC_P1")
		)
		(pad "E5" smd circle
			(at -30.39999 -33.56991 180)
			(size 0.450088 0.450088)
			(layers "F.Cu" "F.Mask" "F.Paste")
			(net "M_K_CPU1_SA_DQ<0>")
		)
		(pad "E6" smd circle
			(at -29.459936 -33.56991 180)
			(size 0.450088 0.450088)
			(layers "F.Cu" "F.Mask" "F.Paste")
			(net "GND")
		)
		(pad "E7" smd circle
			(at -28.519882 -33.56991 180)
			(size 0.450088 0.450088)
			(layers "F.Cu" "F.Mask" "F.Paste")
			(net "GND")
		)
		(pad "E8" smd circle
			(at -27.580082 -33.56991 180)
			(size 0.450088 0.450088)
			(layers "F.Cu" "F.Mask" "F.Paste")
			(net "GND")
		)
		(pad "E9" smd circle
			(at -26.640028 -33.56991 180)
			(size 0.450088 0.450088)
			(layers "F.Cu" "F.Mask" "F.Paste")
			(net "M_L_CPU1_SA_DQ<0>")
		)
		(pad "E10" smd circle
			(at -25.699974 -33.56991 180)
			(size 0.450088 0.450088)
			(layers "F.Cu" "F.Mask" "F.Paste")
			(net "GND")
		)
		(pad "E11" smd circle
			(at -24.75992 -33.56991 180)
			(size 0.450088 0.450088)
			(layers "F.Cu" "F.Mask" "F.Paste")
			(net "PVDDCR_SOC_P1")
		)
		(pad "E12" smd circle
			(at -23.82012 -33.56991 180)
			(size 0.450088 0.450088)
			(layers "F.Cu" "F.Mask" "F.Paste")
			(net "M_H_CPU1_SA_DQ<0>")
		)
		(pad "E13" smd circle
			(at -22.880066 -33.56991 180)
			(size 0.450088 0.450088)
			(layers "F.Cu" "F.Mask" "F.Paste")
			(net "GND")
		)
		(pad "E14" smd circle
			(at -21.940012 -33.56991 180)
			(size 0.450088 0.450088)
			(layers "F.Cu" "F.Mask" "F.Paste")
			(net "GND")
		)
		(pad "E15" smd circle
			(at -20.999958 -33.56991 180)
			(size 0.450088 0.450088)
			(layers "F.Cu" "F.Mask" "F.Paste")
			(net "GND")
		)
		(pad "E16" smd circle
			(at -20.059904 -33.56991 180)
			(size 0.450088 0.450088)
			(layers "F.Cu" "F.Mask" "F.Paste")
			(net "M_J_CPU1_SA_DQ<0>")
		)
		(pad "E17" smd circle
			(at -19.120104 -33.56991 180)
			(size 0.450088 0.450088)
			(layers "F.Cu" "F.Mask" "F.Paste")
			(net "GND")
		)
		(pad "E18" smd circle
			(at -18.18005 -33.56991 180)
			(size 0.450088 0.450088)
			(layers "F.Cu" "F.Mask" "F.Paste")
			(net "GND")
		)
		(pad "E19" smd circle
			(at -17.239996 -33.56991 180)
			(size 0.450088 0.450088)
			(layers "F.Cu" "F.Mask" "F.Paste")
			(net "M_I_CPU1_SA_DQ<0>")
		)
		(pad "E20" smd circle
			(at -16.299942 -33.56991 180)
			(size 0.450088 0.450088)
			(layers "F.Cu" "F.Mask" "F.Paste")
			(net "GND")
		)
		(pad "E21" smd circle
			(at -15.359888 -33.56991 180)
			(size 0.450088 0.450088)
			(layers "F.Cu" "F.Mask" "F.Paste")
			(net "GND")
		)
		(pad "E22" smd circle
			(at -14.420088 -33.56991 180)
			(size 0.450088 0.450088)
			(layers "F.Cu" "F.Mask" "F.Paste")
			(net "PVDDCR_CPU0_P1")
		)
		(pad "E23" smd circle
			(at -13.480034 -33.56991 180)
			(size 0.450088 0.450088)
			(layers "F.Cu" "F.Mask" "F.Paste")
			(net "NC_CPU1_USB00_OC_N")
		)
		(pad "E24" smd circle
			(at -12.53998 -33.56991 180)
			(size 0.450088 0.450088)
			(layers "F.Cu" "F.Mask" "F.Paste")
			(net "NC_CPU1_USB01_OC_N")
		)
		(pad "E25" smd circle
			(at -11.599926 -33.56991 180)
			(size 0.450088 0.450088)
			(layers "F.Cu" "F.Mask" "F.Paste")
			(net "PVDDCR_CPU0_P1")
		)
		(pad "E26" smd circle
			(at -10.659872 -33.56991 180)
			(size 0.450088 0.450088)
			(layers "F.Cu" "F.Mask" "F.Paste")
			(net "NC_CPU1_USB3_USB00_RXN")
		)
		(pad "E27" smd circle
			(at -9.720072 -33.56991 180)
			(size 0.450088 0.450088)
			(layers "F.Cu" "F.Mask" "F.Paste")
			(net "NC_CPU1_USB3_USB00_RXP")
		)
		(pad "E28" smd circle
			(at -8.780018 -33.56991 180)
			(size 0.450088 0.450088)
			(layers "F.Cu" "F.Mask" "F.Paste")
			(net "PVDDCR_CPU0_P1")
		)
		(pad "E29" smd circle
			(at -7.839964 -33.56991 180)
			(size 0.450088 0.450088)
			(layers "F.Cu" "F.Mask" "F.Paste")
			(net "NC_CPU1_USB3_USB01_TXN")
		)
		(pad "E30" smd circle
			(at -6.89991 -33.56991 180)
			(size 0.450088 0.450088)
			(layers "F.Cu" "F.Mask" "F.Paste")
			(net "NC_CPU1_USB3_USB01_TXP")
		)
		(pad "E31" smd circle
			(at -5.96011 -33.56991 180)
			(size 0.450088 0.450088)
			(layers "F.Cu" "F.Mask" "F.Paste")
			(net "PVDDCR_CPU0_P1")
		)
		(pad "E32" smd circle
			(at -5.020056 -33.56991 180)
			(size 0.450088 0.450088)
			(layers "F.Cu" "F.Mask" "F.Paste")
			(net "TP_CPU1_TEST47_CCD3")
		)
		(pad "E33" smd circle
			(at -4.080002 -33.56991 180)
			(size 0.450088 0.450088)
			(layers "F.Cu" "F.Mask" "F.Paste")
			(net "Net_2167")
		)
		(pad "E34" smd circle
			(at -3.139948 -33.56991 180)
			(size 0.450088 0.450088)
			(layers "F.Cu" "F.Mask" "F.Paste")
			(net "PVDDCR_CPU0_P1")
		)
		(pad "E35" smd circle
			(at -2.199894 -33.56991 180)
			(size 0.450088 0.450088)
			(layers "F.Cu" "F.Mask" "F.Paste")
			(net "PVDDCR_CPU0_P1")
		)
		(pad "E36" smd circle
			(at -1.260094 -33.56991 180)
			(size 0.450088 0.450088)
			(layers "F.Cu" "F.Mask" "F.Paste")
			(net "Net_2168")
		)
		(pad "E40" smd circle
			(at 1.560068 -33.56991 180)
			(size 0.450088 0.450088)
			(layers "F.Cu" "F.Mask" "F.Paste")
			(net "P3E_CPU1_P5_RX_DN<1>")
		)
		(pad "E41" smd circle
			(at 2.500122 -33.56991 180)
			(size 0.450088 0.450088)
			(layers "F.Cu" "F.Mask" "F.Paste")
			(net "P3E_CPU1_P5_RX_DP<1>")
		)
		(pad "E42" smd circle
			(at 3.439922 -33.56991 180)
			(size 0.450088 0.450088)
			(layers "F.Cu" "F.Mask" "F.Paste")
			(net "PVDDCR_CPU0_P1")
		)
		(pad "E43" smd circle
			(at 4.379976 -33.56991 180)
			(size 0.450088 0.450088)
			(layers "F.Cu" "F.Mask" "F.Paste")
			(net "P3E_CPU1_P5_RX_DN<0>")
		)
		(pad "E44" smd circle
			(at 5.32003 -33.56991 180)
			(size 0.450088 0.450088)
			(layers "F.Cu" "F.Mask" "F.Paste")
			(net "P3E_CPU1_P5_RX_DP<0>")
		)
		(pad "E45" smd circle
			(at 6.260084 -33.56991 180)
			(size 0.450088 0.450088)
			(layers "F.Cu" "F.Mask" "F.Paste")
			(net "PVDDCR_CPU0_P1")
		)
		(pad "E46" smd circle
			(at 7.199884 -33.56991 180)
			(size 0.450088 0.450088)
			(layers "F.Cu" "F.Mask" "F.Paste")
			(net "WAFL_CPU0_TX0_CPU1_RX1_DP")
		)
		(pad "E47" smd circle
			(at 8.139938 -33.56991 180)
			(size 0.450088 0.450088)
			(layers "F.Cu" "F.Mask" "F.Paste")
			(net "WAFL_CPU0_TX0_CPU1_RX1_DN")
		)
		(pad "E48" smd circle
			(at 9.079992 -33.56991 180)
			(size 0.450088 0.450088)
			(layers "F.Cu" "F.Mask" "F.Paste")
			(net "PVDDCR_CPU0_P1")
		)
		(pad "E49" smd circle
			(at 10.020046 -33.56991 180)
			(size 0.450088 0.450088)
			(layers "F.Cu" "F.Mask" "F.Paste")
			(net "Net_2071")
		)
		(pad "E50" smd circle
			(at 10.9601 -33.56991 180)
			(size 0.450088 0.450088)
			(layers "F.Cu" "F.Mask" "F.Paste")
			(net "Net_2070")
		)
		(pad "E51" smd circle
			(at 11.8999 -33.56991 180)
			(size 0.450088 0.450088)
			(layers "F.Cu" "F.Mask" "F.Paste")
			(net "PVDDCR_CPU0_P1")
		)
		(pad "E52" smd circle
			(at 12.839954 -33.56991 180)
			(size 0.450088 0.450088)
			(layers "F.Cu" "F.Mask" "F.Paste")
			(net "GND")
		)
		(pad "E53" smd circle
			(at 13.780008 -33.56991 180)
			(size 0.450088 0.450088)
			(layers "F.Cu" "F.Mask" "F.Paste")
			(net "GND")
		)
		(pad "E54" smd circle
			(at 14.720062 -33.56991 180)
			(size 0.450088 0.450088)
			(layers "F.Cu" "F.Mask" "F.Paste")
			(net "PVDDCR_CPU0_P1")
		)
		(pad "E55" smd circle
			(at 15.660116 -33.56991 180)
			(size 0.450088 0.450088)
			(layers "F.Cu" "F.Mask" "F.Paste")
			(net "GND")
		)
		(pad "E56" smd circle
			(at 16.599916 -33.56991 180)
			(size 0.450088 0.450088)
			(layers "F.Cu" "F.Mask" "F.Paste")
			(net "GND")
		)
		(pad "E57" smd circle
			(at 17.53997 -33.56991 180)
			(size 0.450088 0.450088)
			(layers "F.Cu" "F.Mask" "F.Paste")
			(net "M_C_CPU1_SA_DQ<0>")
		)
		(pad "E58" smd circle
			(at 18.480024 -33.56991 180)
			(size 0.450088 0.450088)
			(layers "F.Cu" "F.Mask" "F.Paste")
			(net "GND")
		)
		(pad "E59" smd circle
			(at 19.420078 -33.56991 180)
			(size 0.450088 0.450088)
			(layers "F.Cu" "F.Mask" "F.Paste")
			(net "GND")
		)
		(pad "E60" smd circle
			(at 20.359878 -33.56991 180)
			(size 0.450088 0.450088)
			(layers "F.Cu" "F.Mask" "F.Paste")
			(net "M_D_CPU1_SA_DQ<0>")
		)
		(pad "E61" smd circle
			(at 21.299932 -33.56991 180)
			(size 0.450088 0.450088)
			(layers "F.Cu" "F.Mask" "F.Paste")
			(net "GND")
		)
		(pad "E62" smd circle
			(at 22.239986 -33.56991 180)
			(size 0.450088 0.450088)
			(layers "F.Cu" "F.Mask" "F.Paste")
			(net "GND")
		)
		(pad "E63" smd circle
			(at 23.18004 -33.56991 180)
			(size 0.450088 0.450088)
			(layers "F.Cu" "F.Mask" "F.Paste")
			(net "GND")
		)
		(pad "E64" smd circle
			(at 24.120094 -33.56991 180)
			(size 0.450088 0.450088)
			(layers "F.Cu" "F.Mask" "F.Paste")
			(net "M_B_CPU1_SA_DQ<0>")
		)
	)
)
